(kicad_pcb
	(version 20260206)
	(generator "pcbnew")
	(generator_version "10.0")
	(general
		(thickness 1.6)
		(legacy_teardrops no)
	)
	(paper "A4")
	(title_block
		(title "Wiwynn_Tioga_Pass_MB.brd")
		(comment 1 "Tioga Pass / footprints 4481-4487 of 4770")
	)
	(layers
		(0 "F.Cu" signal "TOP")
		(4 "In1.Cu" signal "L2GND")
		(6 "In2.Cu" signal "L3")
		(8 "In3.Cu" signal "L4GND")
		(10 "In4.Cu" signal "L5")
		(12 "In5.Cu" signal "L6GND")
		(14 "In6.Cu" signal "L7VCC")
		(16 "In7.Cu" signal "L8VCC")
		(18 "In8.Cu" signal "L9GND")
		(20 "In9.Cu" signal "L10")
		(22 "In10.Cu" signal "L11GND")
		(24 "In11.Cu" signal "L12")
		(26 "In12.Cu" signal "L13GND")
		(2 "B.Cu" signal "BOTTOM")
		(9 "F.Adhes" user "F.Adhesive")
		(11 "B.Adhes" user "B.Adhesive")
		(13 "F.Paste" user "Package Geometry/Pastemask Top")
		(15 "B.Paste" user "Package Geometry/Pastemask Bottom")
		(5 "F.SilkS" user "Ref Des/Silkscreen Top")
		(7 "B.SilkS" user "Ref Des/Silkscreen Bottom")
		(1 "F.Mask" user "Board Geometry/Soldermask Top")
		(3 "B.Mask" user "Board Geometry/Soldermask Bottom")
		(17 "Dwgs.User" user "User.Drawings")
		(19 "Cmts.User" user "User.Comments")
		(21 "Eco1.User" user "User.Eco1")
		(23 "Eco2.User" user "User.Eco2")
		(25 "Edge.Cuts" user "Board Geometry/Outline")
		(27 "Margin" user)
		(31 "F.CrtYd" user "Package Geometry/Place Bound Top")
		(29 "B.CrtYd" user "Package Geometry/Place Bound Bottom")
		(35 "F.Fab" user "Ref Des/Assembly Top")
		(33 "B.Fab" user "Ref Des/Assembly Bottom")
	)
	(footprint ""
		(layer "B.Cu")
		(at 474.801946 -128.020572 -90)
		(property "Reference" "R1W33"
			(at 0.8382 -0.67818 270)
			(unlocked yes)
			(layer "B.SilkS")
			(effects
				(font
					(size 0.4064 0.254)
					(thickness 0.1524)
				)
				(justify left mirror)
			)
		)
		(property "Value" ""
			(at 0 0 90)
			(layer "B.Fab")
			(effects
				(font
					(size 1.27 1.27)
				)
				(justify mirror)
			)
		)
		(duplicate_pad_numbers_are_jumpers no)
		(fp_poly
			(pts
				(xy 0.2794 -0.1016) (xy -0.2794 -0.1016) (xy -0.2794 0.9906) (xy 0.2794 0.9906)
			)
			(stroke
				(width 0)
				(type default)
			)
			(fill no)
			(layer "B.CrtYd")
		)
		(fp_line
			(start -0.2794 0.9906)
			(end -0.2794 -0.1016)
			(stroke
				(width 0.1)
				(type default)
			)
			(layer "B.Fab")
		)
		(fp_line
			(start 0.2794 0.9906)
			(end -0.2794 0.9906)
			(stroke
				(width 0.1)
				(type default)
			)
			(layer "B.Fab")
		)
		(fp_line
			(start -0.2794 -0.1016)
			(end 0.2794 -0.1016)
			(stroke
				(width 0.1)
				(type default)
			)
			(layer "B.Fab")
		)
		(fp_line
			(start 0.2794 -0.1016)
			(end 0.2794 0.9906)
			(stroke
				(width 0.1)
				(type default)
			)
			(layer "B.Fab")
		)
		(pad "1" smd rect
			(at 0 0 90)
			(size 0.508 0.508)
			(layers "B.Cu" "B.Mask" "B.Paste")
			(net "SMB_DEBUG_STBY_LVC3_SCL_R1")
		)
		(pad "2" smd rect
			(at 0 0.889 90)
			(size 0.508 0.508)
			(layers "B.Cu" "B.Mask" "B.Paste")
			(net "SMB_DEBUG_STBY_LVC3_SCL")
		)
		(zone
			(layer "B.Cu")
			(hatch none 0.5)
			(connect_pads
				(clearance 0)
			)
			(min_thickness 0.25)
			(keepout
				(tracks not_allowed)
				(vias allowed)
				(pads allowed)
				(copperpour not_allowed)
				(footprints allowed)
			)
			(placement
				(enabled no)
				(sheetname "")
			)
			(fill
				(thermal_gap 0.5)
				(thermal_bridge_width 0.5)
				(island_removal_mode 0)
			)
			(polygon
				(pts
					(xy 474.166946 -127.766572) (xy 474.166946 -128.274572) (xy 474.547946 -128.274572) (xy 474.547946 -127.766572)
				)
			)
		)
		(zone
			(layer "B.Cu")
			(hatch none 0.5)
			(connect_pads
				(clearance 0)
			)
			(min_thickness 0.25)
			(keepout
				(tracks allowed)
				(vias not_allowed)
				(pads allowed)
				(copperpour not_allowed)
				(footprints allowed)
			)
			(placement
				(enabled no)
				(sheetname "")
			)
			(fill
				(thermal_gap 0.5)
				(thermal_bridge_width 0.5)
				(island_removal_mode 0)
			)
			(polygon
				(pts
					(xy 474.547946 -127.766572) (xy 474.547946 -128.274572) (xy 474.166946 -128.274572) (xy 474.166946 -127.766572)
				)
			)
		)
	)
	(footprint ""
		(layer "B.Cu")
		(at 338.328 -11.938 90)
		(property "Reference" "R3U4"
			(at 0 0 90)
			(layer "B.SilkS")
			(hide yes)
			(effects
				(font
					(size 1.27 1.27)
				)
				(justify mirror)
			)
		)
		(property "Value" ""
			(at 0 0 90)
			(layer "B.Fab")
			(effects
				(font
					(size 1.27 1.27)
				)
				(justify mirror)
			)
		)
		(duplicate_pad_numbers_are_jumpers no)
		(fp_rect
			(start 0.4953 1.6002)
			(end -0.4953 -0.2032)
			(stroke
				(width 0)
				(type default)
			)
			(fill no)
			(layer "B.CrtYd")
		)
		(fp_line
			(start 0.4953 -0.2032)
			(end -0.4953 -0.2032)
			(stroke
				(width 0.1)
				(type default)
			)
			(layer "B.Fab")
		)
		(fp_line
			(start -0.4953 -0.2032)
			(end -0.4953 1.6002)
			(stroke
				(width 0.1)
				(type default)
			)
			(layer "B.Fab")
		)
		(fp_line
			(start 0.4953 1.6002)
			(end 0.4953 -0.2032)
			(stroke
				(width 0.1)
				(type default)
			)
			(layer "B.Fab")
		)
		(fp_line
			(start -0.4953 1.6002)
			(end 0.4953 1.6002)
			(stroke
				(width 0.1)
				(type default)
			)
			(layer "B.Fab")
		)
		(pad "1" smd rect
			(at 0 0 270)
			(size 0.762 0.889)
			(layers "B.Cu" "B.Mask" "B.Paste")
			(net "PVDDQ_ABC")
		)
		(pad "2" smd rect
			(at 0 1.397 270)
			(size 0.762 0.889)
			(layers "B.Cu" "B.Mask" "B.Paste")
			(net "GND")
		)
		(zone
			(layer "B.Cu")
			(hatch none 0.5)
			(connect_pads
				(clearance 0)
			)
			(min_thickness 0.25)
			(keepout
				(tracks not_allowed)
				(vias allowed)
				(pads allowed)
				(copperpour not_allowed)
				(footprints allowed)
			)
			(placement
				(enabled no)
				(sheetname "")
			)
			(fill
				(thermal_gap 0.5)
				(thermal_bridge_width 0.5)
				(island_removal_mode 0)
			)
			(polygon
				(pts
					(xy 339.2805 -12.319) (xy 338.7725 -12.319) (xy 338.7725 -11.557) (xy 339.2805 -11.557)
				)
			)
		)
		(zone
			(layer "B.Cu")
			(hatch none 0.5)
			(connect_pads
				(clearance 0)
			)
			(min_thickness 0.25)
			(keepout
				(tracks allowed)
				(vias not_allowed)
				(pads allowed)
				(copperpour not_allowed)
				(footprints allowed)
			)
			(placement
				(enabled no)
				(sheetname "")
			)
			(fill
				(thermal_gap 0.5)
				(thermal_bridge_width 0.5)
				(island_removal_mode 0)
			)
			(polygon
				(pts
					(xy 339.2805 -12.319) (xy 338.7725 -12.319) (xy 338.7725 -11.557) (xy 339.2805 -11.557)
				)
			)
		)
	)
	(footprint ""
		(layer "B.Cu")
		(at 9.7536 -41.6814 -90)
		(property "Reference" "R9R9"
			(at 0 0 90)
			(layer "B.SilkS")
			(hide yes)
			(effects
				(font
					(size 1.27 1.27)
				)
				(justify mirror)
			)
		)
		(property "Value" ""
			(at 0 0 90)
			(layer "B.Fab")
			(effects
				(font
					(size 1.27 1.27)
				)
				(justify mirror)
			)
		)
		(duplicate_pad_numbers_are_jumpers no)
		(fp_poly
			(pts
				(xy 0.2794 -0.1016) (xy -0.2794 -0.1016) (xy -0.2794 0.9906) (xy 0.2794 0.9906)
			)
			(stroke
				(width 0)
				(type default)
			)
			(fill no)
			(layer "B.CrtYd")
		)
		(fp_line
			(start -0.2794 0.9906)
			(end -0.2794 -0.1016)
			(stroke
				(width 0.1)
				(type default)
			)
			(layer "B.Fab")
		)
		(fp_line
			(start 0.2794 0.9906)
			(end -0.2794 0.9906)
			(stroke
				(width 0.1)
				(type default)
			)
			(layer "B.Fab")
		)
		(fp_line
			(start -0.2794 -0.1016)
			(end 0.2794 -0.1016)
			(stroke
				(width 0.1)
				(type default)
			)
			(layer "B.Fab")
		)
		(fp_line
			(start 0.2794 -0.1016)
			(end 0.2794 0.9906)
			(stroke
				(width 0.1)
				(type default)
			)
			(layer "B.Fab")
		)
		(pad "1" smd rect
			(at 0 0 90)
			(size 0.508 0.508)
			(layers "B.Cu" "B.Mask" "B.Paste")
			(net "FAN_TACH3")
		)
		(pad "2" smd rect
			(at 0 0.889 90)
			(size 0.508 0.508)
			(layers "B.Cu" "B.Mask" "B.Paste")
			(net "FAN_TACH3_R")
		)
		(zone
			(layer "B.Cu")
			(hatch none 0.5)
			(connect_pads
				(clearance 0)
			)
			(min_thickness 0.25)
			(keepout
				(tracks not_allowed)
				(vias allowed)
				(pads allowed)
				(copperpour not_allowed)
				(footprints allowed)
			)
			(placement
				(enabled no)
				(sheetname "")
			)
			(fill
				(thermal_gap 0.5)
				(thermal_bridge_width 0.5)
				(island_removal_mode 0)
			)
			(polygon
				(pts
					(xy 9.1186 -41.4274) (xy 9.1186 -41.9354) (xy 9.4996 -41.9354) (xy 9.4996 -41.4274)
				)
			)
		)
		(zone
			(layer "B.Cu")
			(hatch none 0.5)
			(connect_pads
				(clearance 0)
			)
			(min_thickness 0.25)
			(keepout
				(tracks allowed)
				(vias not_allowed)
				(pads allowed)
				(copperpour not_allowed)
				(footprints allowed)
			)
			(placement
				(enabled no)
				(sheetname "")
			)
			(fill
				(thermal_gap 0.5)
				(thermal_bridge_width 0.5)
				(island_removal_mode 0)
			)
			(polygon
				(pts
					(xy 9.4996 -41.4274) (xy 9.4996 -41.9354) (xy 9.1186 -41.9354) (xy 9.1186 -41.4274)
				)
			)
		)
	)
	(footprint ""
		(layer "B.Cu")
		(at 346.821506 -2.152904 -90)
		(property "Reference" "C7G42"
			(at 0 0 90)
			(layer "B.SilkS")
			(hide yes)
			(effects
				(font
					(size 1.27 1.27)
				)
				(justify mirror)
			)
		)
		(property "Value" "*"
			(at -1.1811 -2.8194 270)
			(unlocked yes)
			(layer "B.Fab")
			(hide yes)
			(effects
				(font
					(size 1.27 1.016)
					(thickness 0.1524)
				)
				(justify mirror)
			)
		)
		(property "Device Type" "SC1U10V2KX-4-GP_SMD-BCG6-SC1U1A"
			(at -1.1811 -4.3434 270)
			(unlocked yes)
			(layer "B.Fab")
			(hide yes)
			(effects
				(font
					(size 1.27 1.016)
					(thickness 0.1524)
				)
				(justify mirror)
			)
		)
		(duplicate_pad_numbers_are_jumpers no)
		(fp_rect
			(start 0.4318 0.9525)
			(end -0.4318 -0.9525)
			(stroke
				(width 0)
				(type default)
			)
			(fill no)
			(layer "B.CrtYd")
		)
		(fp_rect
			(start 0.4318 0.9525)
			(end -0.4318 -0.9525)
			(stroke
				(width 0)
				(type default)
			)
			(fill no)
			(layer "B.Fab")
		)
		(pad "1" smd custom
			(at 0 -0.4445 90)
			(size 0.1524 0.1524)
			(layers "B.Cu" "B.Mask" "B.Paste")
			(net "P5V_STBY")
			(options
				(clearance outline)
				(anchor circle)
			)
			(primitives
				(gr_poly
					(pts
						(arc
							(start 0.3048 0.2032)
							(mid 0.275042 0.275042)
							(end 0.2032 0.3048)
						)
						(arc
							(start -0.2032 0.3048)
							(mid -0.275042 0.275042)
							(end -0.3048 0.2032)
						)
						(arc
							(start -0.3048 -0.2032)
							(mid -0.275042 -0.275042)
							(end -0.2032 -0.3048)
						)
						(arc
							(start 0.2032 -0.3048)
							(mid 0.275042 -0.275042)
							(end 0.3048 -0.2032)
						)
					)
					(width 0)
					(fill yes)
				)
			)
		)
		(pad "2" smd custom
			(at 0 0.4445 90)
			(size 0.1524 0.1524)
			(layers "B.Cu" "B.Mask" "B.Paste")
			(net "GND")
			(options
				(clearance outline)
				(anchor circle)
			)
			(primitives
				(gr_poly
					(pts
						(arc
							(start 0.3048 0.2032)
							(mid 0.275042 0.275042)
							(end 0.2032 0.3048)
						)
						(arc
							(start -0.2032 0.3048)
							(mid -0.275042 0.275042)
							(end -0.3048 0.2032)
						)
						(arc
							(start -0.3048 -0.2032)
							(mid -0.275042 -0.275042)
							(end -0.2032 -0.3048)
						)
						(arc
							(start 0.2032 -0.3048)
							(mid 0.275042 -0.275042)
							(end 0.3048 -0.2032)
						)
					)
					(width 0)
					(fill yes)
				)
			)
		)
	)
	(footprint ""
		(layer "B.Cu")
		(at 183.3626 -136.4234 180)
		(property "Reference" "C6L10"
			(at 0 0 0)
			(layer "B.SilkS")
			(hide yes)
			(effects
				(font
					(size 1.27 1.27)
				)
				(justify mirror)
			)
		)
		(property "Value" ""
			(at 0 0 0)
			(layer "B.Fab")
			(effects
				(font
					(size 1.27 1.27)
				)
				(justify mirror)
			)
		)
		(duplicate_pad_numbers_are_jumpers no)
		(fp_poly
			(pts
				(xy 0.7239 -0.2159) (xy -0.7239 -0.2159) (xy -0.7239 1.9939) (xy 0.7239 1.9939)
			)
			(stroke
				(width 0)
				(type default)
			)
			(fill no)
			(layer "B.CrtYd")
		)
		(fp_line
			(start 0.7239 1.9939)
			(end -0.7239 1.9939)
			(stroke
				(width 0.1)
				(type default)
			)
			(layer "B.Fab")
		)
		(fp_line
			(start 0.7239 -0.2159)
			(end 0.7239 1.9939)
			(stroke
				(width 0.1)
				(type default)
			)
			(layer "B.Fab")
		)
		(fp_line
			(start -0.7239 1.9939)
			(end -0.7239 -0.2159)
			(stroke
				(width 0.1)
				(type default)
			)
			(layer "B.Fab")
		)
		(fp_line
			(start -0.7239 -0.2159)
			(end 0.7239 -0.2159)
			(stroke
				(width 0.1)
				(type default)
			)
			(layer "B.Fab")
		)
		(pad "1" smd rect
			(at 0 0)
			(size 1.27 1.016)
			(layers "B.Cu" "B.Mask" "B.Paste")
			(net "VR_FET_SW_P12V_STBY_PVPP_KLM")
		)
		(pad "2" smd rect
			(at 0 1.778)
			(size 1.27 1.016)
			(layers "B.Cu" "B.Mask" "B.Paste")
			(net "GND")
		)
		(zone
			(layer "B.Cu")
			(hatch none 0.5)
			(connect_pads
				(clearance 0)
			)
			(min_thickness 0.25)
			(keepout
				(tracks not_allowed)
				(vias allowed)
				(pads allowed)
				(copperpour not_allowed)
				(footprints allowed)
			)
			(placement
				(enabled no)
				(sheetname "")
			)
			(fill
				(thermal_gap 0.5)
				(thermal_bridge_width 0.5)
				(island_removal_mode 0)
			)
			(polygon
				(pts
					(xy 182.7276 -136.9314) (xy 183.9976 -136.9314) (xy 183.9976 -137.6934) (xy 182.7276 -137.6934)
				)
			)
		)
	)
	(footprint ""
		(layer "B.Cu")
		(at 354.543614 -123.780042 -90)
		(property "Reference" "C3M4"
			(at 0 0 90)
			(layer "B.SilkS")
			(hide yes)
			(effects
				(font
					(size 1.27 1.27)
				)
				(justify mirror)
			)
		)
		(property "Value" ""
			(at 0 0 90)
			(layer "B.Fab")
			(effects
				(font
					(size 1.27 1.27)
				)
				(justify mirror)
			)
		)
		(duplicate_pad_numbers_are_jumpers no)
		(fp_poly
			(pts
				(xy -0.3048 -0.1016) (xy -0.3048 0.9906) (xy 0.3048 0.9906) (xy 0.3048 -0.1016)
			)
			(stroke
				(width 0)
				(type default)
			)
			(fill no)
			(layer "B.CrtYd")
		)
		(fp_line
			(start -0.3048 0.9906)
			(end -0.3048 -0.1016)
			(stroke
				(width 0.1)
				(type default)
			)
			(layer "B.Fab")
		)
		(fp_line
			(start 0.3048 0.9906)
			(end -0.3048 0.9906)
			(stroke
				(width 0.1)
				(type default)
			)
			(layer "B.Fab")
		)
		(fp_line
			(start -0.3048 -0.1016)
			(end 0.3048 -0.1016)
			(stroke
				(width 0.1)
				(type default)
			)
			(layer "B.Fab")
		)
		(fp_line
			(start 0.3048 -0.1016)
			(end 0.3048 0.9906)
			(stroke
				(width 0.1)
				(type default)
			)
			(layer "B.Fab")
		)
		(pad "1" smd rect
			(at 0 0 90)
			(size 0.508 0.508)
			(layers "B.Cu" "B.Mask" "B.Paste")
			(net "P3E_CPU0_PE1_PCH_R_RXN<12>")
		)
		(pad "2" smd rect
			(at 0 0.889 90)
			(size 0.508 0.508)
			(layers "B.Cu" "B.Mask" "B.Paste")
			(net "P3E_CPU0_PE1_PCH_RXN<12>")
		)
		(zone
			(layer "B.Cu")
			(hatch none 0.5)
			(connect_pads
				(clearance 0)
			)
			(min_thickness 0.25)
			(keepout
				(tracks not_allowed)
				(vias allowed)
				(pads allowed)
				(copperpour not_allowed)
				(footprints allowed)
			)
			(placement
				(enabled no)
				(sheetname "")
			)
			(fill
				(thermal_gap 0.5)
				(thermal_bridge_width 0.5)
				(island_removal_mode 0)
			)
			(polygon
				(pts
					(xy 353.908614 -123.526042) (xy 353.908614 -124.034042) (xy 354.289614 -124.034042) (xy 354.289614 -123.526042)
				)
			)
		)
		(zone
			(layer "B.Cu")
			(hatch none 0.5)
			(connect_pads
				(clearance 0)
			)
			(min_thickness 0.25)
			(keepout
				(tracks allowed)
				(vias not_allowed)
				(pads allowed)
				(copperpour not_allowed)
				(footprints allowed)
			)
			(placement
				(enabled no)
				(sheetname "")
			)
			(fill
				(thermal_gap 0.5)
				(thermal_bridge_width 0.5)
				(island_removal_mode 0)
			)
			(polygon
				(pts
					(xy 354.289614 -123.526042) (xy 354.289614 -124.034042) (xy 353.908614 -124.034042) (xy 353.908614 -123.526042)
				)
			)
		)
	)
	(footprint ""
		(layer "B.Cu")
		(at 273.179286 -73.51014)
		(property "Reference" "C5P29"
			(at 0 0 0)
			(layer "B.SilkS")
			(hide yes)
			(effects
				(font
					(size 1.27 1.27)
				)
				(justify mirror)
			)
		)
		(property "Value" ""
			(at 0 0 0)
			(layer "B.Fab")
			(effects
				(font
					(size 1.27 1.27)
				)
				(justify mirror)
			)
		)
		(duplicate_pad_numbers_are_jumpers no)
		(fp_poly
			(pts
				(xy 0.7239 -0.2159) (xy -0.7239 -0.2159) (xy -0.7239 1.9939) (xy 0.7239 1.9939)
			)
			(stroke
				(width 0)
				(type default)
			)
			(fill no)
			(layer "B.CrtYd")
		)
		(fp_line
			(start -0.7239 -0.2159)
			(end 0.7239 -0.2159)
			(stroke
				(width 0.1)
				(type default)
			)
			(layer "B.Fab")
		)
		(fp_line
			(start -0.7239 1.9939)
			(end -0.7239 -0.2159)
			(stroke
				(width 0.1)
				(type default)
			)
			(layer "B.Fab")
		)
		(fp_line
			(start 0.7239 -0.2159)
			(end 0.7239 1.9939)
			(stroke
				(width 0.1)
				(type default)
			)
			(layer "B.Fab")
		)
		(fp_line
			(start 0.7239 1.9939)
			(end -0.7239 1.9939)
			(stroke
				(width 0.1)
				(type default)
			)
			(layer "B.Fab")
		)
		(pad "1" smd rect
			(at 0 0 180)
			(size 1.27 1.016)
			(layers "B.Cu" "B.Mask" "B.Paste")
			(net "PVCCMCP_CPU0")
		)
		(pad "2" smd rect
			(at 0 1.778 180)
			(size 1.27 1.016)
			(layers "B.Cu" "B.Mask" "B.Paste")
			(net "GND")
		)
		(zone
			(layer "B.Cu")
			(hatch none 0.5)
			(connect_pads
				(clearance 0)
			)
			(min_thickness 0.25)
			(keepout
				(tracks not_allowed)
				(vias allowed)
				(pads allowed)
				(copperpour not_allowed)
				(footprints allowed)
			)
			(placement
				(enabled no)
				(sheetname "")
			)
			(fill
				(thermal_gap 0.5)
				(thermal_bridge_width 0.5)
				(island_removal_mode 0)
			)
			(polygon
				(pts
					(xy 273.814286 -73.00214) (xy 272.544286 -73.00214) (xy 272.544286 -72.24014) (xy 273.814286 -72.24014)
				)
			)
		)
	)
)
